(kicad_pcb
	(version 20260206)
	(generator "pcbnew")
	(generator_version "10.0")
	(general
		(thickness 1.6)
		(legacy_teardrops no)
	)
	(paper "A4")
	(title_block
		(title "01162023_DA0F0TEBIF0_F0T_Expander_BD_F_brd_V02_OCP.brd")
		(comment 1 "Grand Teton / footprints 1258-1265 of 9728")
	)
	(layers
		(0 "F.Cu" signal "TOP")
		(4 "In1.Cu" signal "GND")
		(6 "In2.Cu" signal "VCC")
		(8 "In3.Cu" signal "VCC1")
		(10 "In4.Cu" signal "GND1")
		(12 "In5.Cu" signal "IN1")
		(14 "In6.Cu" signal "GND2")
		(16 "In7.Cu" signal "IN2")
		(18 "In8.Cu" signal "GND3")
		(20 "In9.Cu" signal "IN3")
		(22 "In10.Cu" signal "GND4")
		(24 "In11.Cu" signal "IN4")
		(26 "In12.Cu" signal "GND5")
		(28 "In13.Cu" signal "IN5")
		(30 "In14.Cu" signal "GND6")
		(32 "In15.Cu" signal "IN6")
		(34 "In16.Cu" signal "GND7")
		(2 "B.Cu" signal "BOTTOM")
		(9 "F.Adhes" user "F.Adhesive")
		(11 "B.Adhes" user "B.Adhesive")
		(13 "F.Paste" user "Package Geometry/Pastemask Top")
		(15 "B.Paste" user "Package Geometry/Pastemask Bottom")
		(5 "F.SilkS" user "Ref Des/Silkscreen Top")
		(7 "B.SilkS" user "Ref Des/Silkscreen Bottom")
		(1 "F.Mask" user "Board Geometry/Soldermask Top")
		(3 "B.Mask" user "Board Geometry/Soldermask Bottom")
		(17 "Dwgs.User" user "User.Drawings")
		(19 "Cmts.User" user "User.Comments")
		(21 "Eco1.User" user "User.Eco1")
		(23 "Eco2.User" user "User.Eco2")
		(25 "Edge.Cuts" user "Board Geometry/Outline")
		(27 "Margin" user)
		(31 "F.CrtYd" user "Package Geometry/Place Bound Top")
		(29 "B.CrtYd" user "Package Geometry/Place Bound Bottom")
		(35 "F.Fab" user "Ref Des/Assembly Top")
		(33 "B.Fab" user "Ref Des/Assembly Bottom")
	)
	(footprint ""
		(layer "F.Cu")
		(at 330.05014 -95.263716 -90)
		(property "Reference" "PR198"
			(at 0 0 270)
			(layer "F.SilkS")
			(hide yes)
			(effects
				(font
					(size 1.27 1.27)
				)
			)
		)
		(property "Value" ""
			(at 0 0 270)
			(layer "F.Fab")
			(effects
				(font
					(size 1.27 1.27)
				)
			)
		)
		(duplicate_pad_numbers_are_jumpers no)
		(fp_line
			(start -0.7874 0.4064)
			(end -0.7874 -0.4064)
			(stroke
				(width 0.1524)
				(type default)
			)
			(layer "F.SilkS")
		)
		(fp_line
			(start 0.7874 0.4064)
			(end -0.7874 0.4064)
			(stroke
				(width 0.1524)
				(type default)
			)
			(layer "F.SilkS")
		)
		(fp_line
			(start -0.7874 -0.4064)
			(end 0.7874 -0.4064)
			(stroke
				(width 0.1524)
				(type default)
			)
			(layer "F.SilkS")
		)
		(fp_line
			(start 0.7874 -0.4064)
			(end 0.7874 0.4064)
			(stroke
				(width 0.1524)
				(type default)
			)
			(layer "F.SilkS")
		)
		(fp_line
			(start -0.67945 0.3048)
			(end -0.67945 -0.305054)
			(stroke
				(width 0.1)
				(type default)
			)
			(layer "F.Fab")
		)
		(fp_line
			(start -0.12065 0.3048)
			(end -0.67945 0.3048)
			(stroke
				(width 0.1)
				(type default)
			)
			(layer "F.Fab")
		)
		(fp_line
			(start 0.120396 0.3048)
			(end 0.120396 0.2794)
			(stroke
				(width 0.1)
				(type default)
			)
			(layer "F.Fab")
		)
		(fp_line
			(start 0.67945 0.3048)
			(end 0.120396 0.3048)
			(stroke
				(width 0.1)
				(type default)
			)
			(layer "F.Fab")
		)
		(fp_line
			(start -0.12065 0.2794)
			(end -0.12065 0.3048)
			(stroke
				(width 0.1)
				(type default)
			)
			(layer "F.Fab")
		)
		(fp_line
			(start 0.120396 0.2794)
			(end -0.12065 0.2794)
			(stroke
				(width 0.1)
				(type default)
			)
			(layer "F.Fab")
		)
		(fp_line
			(start -0.12065 -0.2794)
			(end 0.12065 -0.2794)
			(stroke
				(width 0.1)
				(type default)
			)
			(layer "F.Fab")
		)
		(fp_line
			(start 0.12065 -0.2794)
			(end 0.12065 -0.3048)
			(stroke
				(width 0.1)
				(type default)
			)
			(layer "F.Fab")
		)
		(fp_line
			(start 0.12065 -0.3048)
			(end 0.67945 -0.3048)
			(stroke
				(width 0.1)
				(type default)
			)
			(layer "F.Fab")
		)
		(fp_line
			(start 0.67945 -0.3048)
			(end 0.67945 0.3048)
			(stroke
				(width 0.1)
				(type default)
			)
			(layer "F.Fab")
		)
		(fp_line
			(start -0.67945 -0.305054)
			(end -0.12065 -0.305054)
			(stroke
				(width 0.1)
				(type default)
			)
			(layer "F.Fab")
		)
		(fp_line
			(start -0.12065 -0.305054)
			(end -0.12065 -0.2794)
			(stroke
				(width 0.1)
				(type default)
			)
			(layer "F.Fab")
		)
		(pad "1" smd circle
			(at -0.40005 0 270)
			(size 0 0)
			(layers "F.Cu" "F.Mask" "F.Paste")
			(net "P12V_NIC5_OCP")
		)
		(pad "2" smd circle
			(at 0.40005 0 270)
			(size 0 0)
			(layers "F.Cu" "F.Mask" "F.Paste")
			(net "GND")
		)
	)
	(footprint ""
		(layer "F.Cu")
		(at 390.288018 -45.704252 90)
		(property "Reference" "R649"
			(at 0 0 90)
			(layer "F.SilkS")
			(hide yes)
			(effects
				(font
					(size 1.27 1.27)
				)
			)
		)
		(property "Value" ""
			(at 0 0 90)
			(layer "F.Fab")
			(effects
				(font
					(size 1.27 1.27)
				)
			)
		)
		(duplicate_pad_numbers_are_jumpers no)
		(fp_line
			(start 3.937508 -1.8796)
			(end -3.937508 -1.8796)
			(stroke
				(width 0.1524)
				(type default)
			)
			(layer "F.SilkS")
		)
		(fp_line
			(start -3.937508 -1.8796)
			(end -3.937508 1.8796)
			(stroke
				(width 0.1524)
				(type default)
			)
			(layer "F.SilkS")
		)
		(fp_line
			(start 3.937508 1.8796)
			(end 3.937508 -1.8796)
			(stroke
				(width 0.1524)
				(type default)
			)
			(layer "F.SilkS")
		)
		(fp_line
			(start -3.937508 1.8796)
			(end 3.937508 1.8796)
			(stroke
				(width 0.1524)
				(type default)
			)
			(layer "F.SilkS")
		)
		(fp_line
			(start 3.275076 -1.674876)
			(end -3.275076 -1.674876)
			(stroke
				(width 0.1)
				(type default)
			)
			(layer "F.Fab")
		)
		(fp_line
			(start -3.275076 -1.674876)
			(end -3.275076 1.674876)
			(stroke
				(width 0.1)
				(type default)
			)
			(layer "F.Fab")
		)
		(fp_line
			(start 3.275076 1.674876)
			(end 3.275076 -1.674876)
			(stroke
				(width 0.1)
				(type default)
			)
			(layer "F.Fab")
		)
		(fp_line
			(start -3.275076 1.674876)
			(end 3.275076 1.674876)
			(stroke
				(width 0.1)
				(type default)
			)
			(layer "F.Fab")
		)
		(pad "1" smd rect
			(at -2.350008 0 90)
			(size 2.921 3.5052)
			(layers "F.Cu" "F.Mask" "F.Paste")
			(net "P12V_SSD13")
		)
		(pad "2" smd rect
			(at 2.350008 0 90)
			(size 2.921 3.5052)
			(layers "F.Cu" "F.Mask" "F.Paste")
			(net "P12V_SSD13_R")
		)
	)
	(footprint ""
		(layer "F.Cu")
		(at 331.350112 -289.820096)
		(property "Reference" "H140"
			(at -1.30429 4.559808 0)
			(unlocked yes)
			(layer "F.SilkS")
			(effects
				(font
					(size 0.7874 0.5842)
					(thickness 0.1524)
				)
				(justify left)
			)
		)
		(property "Value" ""
			(at 0 0 0)
			(layer "F.Fab")
			(effects
				(font
					(size 1.27 1.27)
				)
			)
		)
		(duplicate_pad_numbers_are_jumpers no)
		(pad "1" thru_hole circle
			(at 0 0)
			(size 6.5024 6.5024)
			(drill 3.2004)
			(layers "*.Cu" "*.Mask")
			(remove_unused_layers no)
			(net "GND")
			(clearance -1.397)
		)
	)
	(footprint ""
		(layer "F.Cu")
		(at 330.63434 -30.94609 180)
		(property "Reference" "C515"
			(at 0 0 180)
			(layer "F.SilkS")
			(hide yes)
			(effects
				(font
					(size 1.27 1.27)
				)
			)
		)
		(property "Value" ""
			(at 0 0 180)
			(layer "F.Fab")
			(effects
				(font
					(size 1.27 1.27)
				)
			)
		)
		(duplicate_pad_numbers_are_jumpers no)
		(fp_line
			(start 0.299974 0.150114)
			(end -0.299974 0.150114)
			(stroke
				(width 0.1)
				(type default)
			)
			(layer "F.Fab")
		)
		(fp_line
			(start 0.299974 -0.150114)
			(end 0.299974 0.150114)
			(stroke
				(width 0.1)
				(type default)
			)
			(layer "F.Fab")
		)
		(fp_line
			(start -0.299974 0.150114)
			(end -0.299974 -0.150114)
			(stroke
				(width 0.1)
				(type default)
			)
			(layer "F.Fab")
		)
		(fp_line
			(start -0.299974 -0.150114)
			(end 0.299974 -0.150114)
			(stroke
				(width 0.1)
				(type default)
			)
			(layer "F.Fab")
		)
		(pad "1" smd rect
			(at -0.2667 0 180)
			(size 0.3048 0.381)
			(layers "F.Cu" "F.Mask" "F.Paste")
			(net "P5E_PEX2_STN2_TX_DP<33>")
		)
		(pad "2" smd rect
			(at 0.2667 0 180)
			(size 0.3048 0.381)
			(layers "F.Cu" "F.Mask" "F.Paste")
			(net "P5E_PEX2_STN2_TX_C_DP<33>")
		)
	)
	(footprint ""
		(layer "F.Cu")
		(at 452.543672 -45.88891)
		(property "Reference" "R675"
			(at 0 0 0)
			(layer "F.SilkS")
			(hide yes)
			(effects
				(font
					(size 1.27 1.27)
				)
			)
		)
		(property "Value" ""
			(at 0 0 0)
			(layer "F.Fab")
			(effects
				(font
					(size 1.27 1.27)
				)
			)
		)
		(duplicate_pad_numbers_are_jumpers no)
		(fp_line
			(start -0.7874 -0.4064)
			(end 0.7874 -0.4064)
			(stroke
				(width 0.1524)
				(type default)
			)
			(layer "F.SilkS")
		)
		(fp_line
			(start -0.7874 0.4064)
			(end -0.7874 -0.4064)
			(stroke
				(width 0.1524)
				(type default)
			)
			(layer "F.SilkS")
		)
		(fp_line
			(start 0.7874 -0.4064)
			(end 0.7874 0.4064)
			(stroke
				(width 0.1524)
				(type default)
			)
			(layer "F.SilkS")
		)
		(fp_line
			(start 0.7874 0.4064)
			(end -0.7874 0.4064)
			(stroke
				(width 0.1524)
				(type default)
			)
			(layer "F.SilkS")
		)
		(fp_line
			(start -0.67945 -0.305054)
			(end -0.12065 -0.305054)
			(stroke
				(width 0.1)
				(type default)
			)
			(layer "F.Fab")
		)
		(fp_line
			(start -0.67945 0.3048)
			(end -0.67945 -0.305054)
			(stroke
				(width 0.1)
				(type default)
			)
			(layer "F.Fab")
		)
		(fp_line
			(start -0.12065 -0.305054)
			(end -0.12065 -0.2794)
			(stroke
				(width 0.1)
				(type default)
			)
			(layer "F.Fab")
		)
		(fp_line
			(start -0.12065 -0.2794)
			(end 0.12065 -0.2794)
			(stroke
				(width 0.1)
				(type default)
			)
			(layer "F.Fab")
		)
		(fp_line
			(start -0.12065 0.2794)
			(end -0.12065 0.3048)
			(stroke
				(width 0.1)
				(type default)
			)
			(layer "F.Fab")
		)
		(fp_line
			(start -0.12065 0.3048)
			(end -0.67945 0.3048)
			(stroke
				(width 0.1)
				(type default)
			)
			(layer "F.Fab")
		)
		(fp_line
			(start 0.120396 0.2794)
			(end -0.12065 0.2794)
			(stroke
				(width 0.1)
				(type default)
			)
			(layer "F.Fab")
		)
		(fp_line
			(start 0.120396 0.3048)
			(end 0.120396 0.2794)
			(stroke
				(width 0.1)
				(type default)
			)
			(layer "F.Fab")
		)
		(fp_line
			(start 0.12065 -0.3048)
			(end 0.67945 -0.3048)
			(stroke
				(width 0.1)
				(type default)
			)
			(layer "F.Fab")
		)
		(fp_line
			(start 0.12065 -0.2794)
			(end 0.12065 -0.3048)
			(stroke
				(width 0.1)
				(type default)
			)
			(layer "F.Fab")
		)
		(fp_line
			(start 0.67945 -0.3048)
			(end 0.67945 0.3048)
			(stroke
				(width 0.1)
				(type default)
			)
			(layer "F.Fab")
		)
		(fp_line
			(start 0.67945 0.3048)
			(end 0.120396 0.3048)
			(stroke
				(width 0.1)
				(type default)
			)
			(layer "F.Fab")
		)
		(pad "1" smd circle
			(at -0.40005 0)
			(size 0 0)
			(layers "F.Cu" "F.Mask" "F.Paste")
			(net "SSD15_ADC_A0")
		)
		(pad "2" smd circle
			(at 0.40005 0)
			(size 0 0)
			(layers "F.Cu" "F.Mask" "F.Paste")
			(net "GND")
		)
	)
	(footprint ""
		(layer "F.Cu")
		(at 379.889512 -63.56223)
		(property "Reference" "Q209"
			(at -0.018796 -2.381758 0)
			(unlocked yes)
			(layer "F.SilkS")
			(effects
				(font
					(size 0.7874 0.5842)
					(thickness 0.1524)
				)
			)
		)
		(property "Value" ""
			(at 0 0 0)
			(layer "F.Fab")
			(effects
				(font
					(size 1.27 1.27)
				)
			)
		)
		(duplicate_pad_numbers_are_jumpers no)
		(fp_line
			(start -1.376172 -1.199896)
			(end -0.508 -1.199896)
			(stroke
				(width 0.1524)
				(type default)
			)
			(layer "F.SilkS")
		)
		(fp_line
			(start -1.376172 1.199896)
			(end -1.376172 -1.199896)
			(stroke
				(width 0.1524)
				(type default)
			)
			(layer "F.SilkS")
		)
		(fp_line
			(start -0.508 -1.199896)
			(end 0 -0.762)
			(stroke
				(width 0.1524)
				(type default)
			)
			(layer "F.SilkS")
		)
		(fp_line
			(start 0 -0.762)
			(end 0.508 -1.199896)
			(stroke
				(width 0.1524)
				(type default)
			)
			(layer "F.SilkS")
		)
		(fp_line
			(start 0.508 -1.199896)
			(end 1.376172 -1.199896)
			(stroke
				(width 0.1524)
				(type default)
			)
			(layer "F.SilkS")
		)
		(fp_line
			(start 1.376172 -1.199896)
			(end 1.376172 1.199896)
			(stroke
				(width 0.1524)
				(type default)
			)
			(layer "F.SilkS")
		)
		(fp_line
			(start 1.376172 1.199896)
			(end -1.376172 1.199896)
			(stroke
				(width 0.1524)
				(type default)
			)
			(layer "F.SilkS")
		)
		(fp_poly
			(pts
				(xy -1.452626 -1.070864) (xy -1.721866 -1.879092) (xy -2.260854 -1.340104)
			)
			(stroke
				(width 0)
				(type default)
			)
			(fill yes)
			(layer "F.SilkS")
		)
		(fp_line
			(start -0.674878 -1.100074)
			(end 0.674878 -1.100074)
			(stroke
				(width 0.1)
				(type default)
			)
			(layer "F.Fab")
		)
		(fp_line
			(start -0.674878 1.100074)
			(end -0.674878 -1.100074)
			(stroke
				(width 0.1)
				(type default)
			)
			(layer "F.Fab")
		)
		(fp_line
			(start 0.674878 -1.100074)
			(end 0.674878 1.100074)
			(stroke
				(width 0.1)
				(type default)
			)
			(layer "F.Fab")
		)
		(fp_line
			(start 0.674878 1.100074)
			(end -0.674878 1.100074)
			(stroke
				(width 0.1)
				(type default)
			)
			(layer "F.Fab")
		)
		(fp_poly
			(pts
				(xy -1.4605 -0.7493) (xy -2.2225 -1.1303) (xy -2.2225 -0.3683)
			)
			(stroke
				(width 0)
				(type default)
			)
			(fill yes)
			(layer "F.Fab")
		)
		(pad "1" smd rect
			(at -0.899922 -0.750062 270)
			(size 0.6096 0.6096)
			(layers "F.Cu" "F.Mask" "F.Paste")
			(net "GND")
		)
		(pad "2" smd rect
			(at -0.899922 0 270)
			(size 0.4064 0.6096)
			(layers "F.Cu" "F.Mask" "F.Paste")
			(net "P12V_SSD13_PG_G1")
		)
		(pad "3" smd rect
			(at -0.899922 0.750062 270)
			(size 0.6096 0.6096)
			(layers "F.Cu" "F.Mask" "F.Paste")
			(net "PWRGD_P12V_SSD13_D")
		)
		(pad "4" smd rect
			(at 0.899922 0.750062 270)
			(size 0.6096 0.6096)
			(layers "F.Cu" "F.Mask" "F.Paste")
			(net "GND")
		)
		(pad "5" smd rect
			(at 0.899922 0 270)
			(size 0.4064 0.6096)
			(layers "F.Cu" "F.Mask" "F.Paste")
			(net "P12V_SSD13_PG_G2")
		)
		(pad "6" smd rect
			(at 0.899922 -0.750062 270)
			(size 0.6096 0.6096)
			(layers "F.Cu" "F.Mask" "F.Paste")
			(net "P12V_SSD13_PG_G2")
		)
	)
	(footprint ""
		(layer "F.Cu")
		(at 169.759884 -199.932798)
		(property "Reference" "R3287"
			(at 0 0 0)
			(layer "F.SilkS")
			(hide yes)
			(effects
				(font
					(size 1.27 1.27)
				)
			)
		)
		(property "Value" ""
			(at 0 0 0)
			(layer "F.Fab")
			(effects
				(font
					(size 1.27 1.27)
				)
			)
		)
		(duplicate_pad_numbers_are_jumpers no)
		(fp_line
			(start -0.7874 -0.4064)
			(end 0.7874 -0.4064)
			(stroke
				(width 0.1524)
				(type default)
			)
			(layer "F.SilkS")
		)
		(fp_line
			(start -0.7874 0.4064)
			(end -0.7874 -0.4064)
			(stroke
				(width 0.1524)
				(type default)
			)
			(layer "F.SilkS")
		)
		(fp_line
			(start 0.7874 -0.4064)
			(end 0.7874 0.4064)
			(stroke
				(width 0.1524)
				(type default)
			)
			(layer "F.SilkS")
		)
		(fp_line
			(start 0.7874 0.4064)
			(end -0.7874 0.4064)
			(stroke
				(width 0.1524)
				(type default)
			)
			(layer "F.SilkS")
		)
		(fp_line
			(start -0.67945 -0.305054)
			(end -0.12065 -0.305054)
			(stroke
				(width 0.1)
				(type default)
			)
			(layer "F.Fab")
		)
		(fp_line
			(start -0.67945 0.3048)
			(end -0.67945 -0.305054)
			(stroke
				(width 0.1)
				(type default)
			)
			(layer "F.Fab")
		)
		(fp_line
			(start -0.12065 -0.305054)
			(end -0.12065 -0.2794)
			(stroke
				(width 0.1)
				(type default)
			)
			(layer "F.Fab")
		)
		(fp_line
			(start -0.12065 -0.2794)
			(end 0.12065 -0.2794)
			(stroke
				(width 0.1)
				(type default)
			)
			(layer "F.Fab")
		)
		(fp_line
			(start -0.12065 0.2794)
			(end -0.12065 0.3048)
			(stroke
				(width 0.1)
				(type default)
			)
			(layer "F.Fab")
		)
		(fp_line
			(start -0.12065 0.3048)
			(end -0.67945 0.3048)
			(stroke
				(width 0.1)
				(type default)
			)
			(layer "F.Fab")
		)
		(fp_line
			(start 0.120396 0.2794)
			(end -0.12065 0.2794)
			(stroke
				(width 0.1)
				(type default)
			)
			(layer "F.Fab")
		)
		(fp_line
			(start 0.120396 0.3048)
			(end 0.120396 0.2794)
			(stroke
				(width 0.1)
				(type default)
			)
			(layer "F.Fab")
		)
		(fp_line
			(start 0.12065 -0.3048)
			(end 0.67945 -0.3048)
			(stroke
				(width 0.1)
				(type default)
			)
			(layer "F.Fab")
		)
		(fp_line
			(start 0.12065 -0.2794)
			(end 0.12065 -0.3048)
			(stroke
				(width 0.1)
				(type default)
			)
			(layer "F.Fab")
		)
		(fp_line
			(start 0.67945 -0.3048)
			(end 0.67945 0.3048)
			(stroke
				(width 0.1)
				(type default)
			)
			(layer "F.Fab")
		)
		(fp_line
			(start 0.67945 0.3048)
			(end 0.120396 0.3048)
			(stroke
				(width 0.1)
				(type default)
			)
			(layer "F.Fab")
		)
		(pad "1" smd circle
			(at -0.40005 0)
			(size 0 0)
			(layers "F.Cu" "F.Mask" "F.Paste")
			(net "SPI_BIC1_CS0_LS01_R_N")
		)
		(pad "2" smd circle
			(at 0.40005 0)
			(size 0 0)
			(layers "F.Cu" "F.Mask" "F.Paste")
			(net "SPI_BIC1_CS0_LS01_N")
		)
	)
	(footprint ""
		(layer "F.Cu")
		(at 435.24043 -143.182848 90)
		(property "Reference" "C4005"
			(at 0 0 90)
			(layer "F.SilkS")
			(hide yes)
			(effects
				(font
					(size 1.27 1.27)
				)
			)
		)
		(property "Value" ""
			(at 0 0 90)
			(layer "F.Fab")
			(effects
				(font
					(size 1.27 1.27)
				)
			)
		)
		(duplicate_pad_numbers_are_jumpers no)
		(fp_line
			(start 0.7874 -0.4064)
			(end 0.7874 0.4064)
			(stroke
				(width 0.1524)
				(type default)
			)
			(layer "F.SilkS")
		)
		(fp_line
			(start -0.7874 -0.4064)
			(end 0.7874 -0.4064)
			(stroke
				(width 0.1524)
				(type default)
			)
			(layer "F.SilkS")
		)
		(fp_line
			(start 0.7874 0.4064)
			(end -0.7874 0.4064)
			(stroke
				(width 0.1524)
				(type default)
			)
			(layer "F.SilkS")
		)
		(fp_line
			(start -0.7874 0.4064)
			(end -0.7874 -0.4064)
			(stroke
				(width 0.1524)
				(type default)
			)
			(layer "F.SilkS")
		)
		(fp_line
			(start -0.12065 -0.305054)
			(end -0.12065 -0.2794)
			(stroke
				(width 0.1)
				(type default)
			)
			(layer "F.Fab")
		)
		(fp_line
			(start -0.67945 -0.305054)
			(end -0.12065 -0.305054)
			(stroke
				(width 0.1)
				(type default)
			)
			(layer "F.Fab")
		)
		(fp_line
			(start 0.67945 -0.3048)
			(end 0.67945 0.3048)
			(stroke
				(width 0.1)
				(type default)
			)
			(layer "F.Fab")
		)
		(fp_line
			(start 0.12065 -0.3048)
			(end 0.67945 -0.3048)
			(stroke
				(width 0.1)
				(type default)
			)
			(layer "F.Fab")
		)
		(fp_line
			(start 0.12065 -0.2794)
			(end 0.12065 -0.3048)
			(stroke
				(width 0.1)
				(type default)
			)
			(layer "F.Fab")
		)
		(fp_line
			(start -0.12065 -0.2794)
			(end 0.12065 -0.2794)
			(stroke
				(width 0.1)
				(type default)
			)
			(layer "F.Fab")
		)
		(fp_line
			(start 0.120396 0.2794)
			(end -0.12065 0.2794)
			(stroke
				(width 0.1)
				(type default)
			)
			(layer "F.Fab")
		)
		(fp_line
			(start -0.12065 0.2794)
			(end -0.12065 0.3048)
			(stroke
				(width 0.1)
				(type default)
			)
			(layer "F.Fab")
		)
		(fp_line
			(start 0.67945 0.3048)
			(end 0.120396 0.3048)
			(stroke
				(width 0.1)
				(type default)
			)
			(layer "F.Fab")
		)
		(fp_line
			(start 0.120396 0.3048)
			(end 0.120396 0.2794)
			(stroke
				(width 0.1)
				(type default)
			)
			(layer "F.Fab")
		)
		(fp_line
			(start -0.12065 0.3048)
			(end -0.67945 0.3048)
			(stroke
				(width 0.1)
				(type default)
			)
			(layer "F.Fab")
		)
		(fp_line
			(start -0.67945 0.3048)
			(end -0.67945 -0.305054)
			(stroke
				(width 0.1)
				(type default)
			)
			(layer "F.Fab")
		)
		(pad "1" smd circle
			(at -0.40005 0 90)
			(size 0 0)
			(layers "F.Cu" "F.Mask" "F.Paste")
			(net "PRSNT_NIC7_R_N")
		)
		(pad "2" smd circle
			(at 0.40005 0 90)
			(size 0 0)
			(layers "F.Cu" "F.Mask" "F.Paste")
			(net "GND")
		)
	)
)
